FILE_TYPE = MULTI_PHYS_TABLE;
PART 'NC7SB3157'
{==========================================================================================================================================================}
:PACK_TYPE|MATERIAL|PART_NUMBER= EnvComp |PART_NUMBER|JEDEC_TYPE|CLASS|DESCRIPTION|HEIGHT|COMPONENT_TYPE|LEAD_LENGTH| LPID   | SPEED_URL | Status |RPL| AML | Bus_Unit | Days ;
{==========================================================================================================================================================}
'SMLF'     | 'IC'     | 'C99406-001'(!) = 'YES;YES;YES;UNK;ok;VLD' | 'C99406-001' | 'SSOP6_53_65MA' | 'IC'  | 'SPDT ANALOG SW' | '.037 IN' | 'SMALLSMT'     | '' | '' | 'http://speed.intel.com:8081/speed/module/pdm/item/pdm_item_detail_direct.asp?item_cde=C99406-001&item_rev=01&url_param=unused' | 'Conditional' | 'YES' | '2' | 'SMO_IC' | '70' 
'SMLF'     | 'EMPTY'  | 'C99406-001'(!) = 'YES;YES;YES;UNK;ok;VLD' | 'C99406-001' | 'SSOP6_53_65MA' | 'IO'  | 'SPDT ANALOG SW' | '.037 IN' | 'SMALLSMT'     | '' | '' | 'http://speed.intel.com:8081/speed/module/pdm/item/pdm_item_detail_direct.asp?item_cde=C99406-001&item_rev=01&url_param=unused' | 'Conditional' | 'YES' | '2' | 'SMO_IC' | '70' 
END_PART
END.
